(kicad_pcb
	(version 20260206)
	(generator "pcbnew")
	(generator_version "10.0")
	(general
		(thickness 1.6)
		(legacy_teardrops no)
	)
	(paper "A4")
	(title_block
		(title "Bryce Canyon_F.DPB_16315-1-OCP.brd")
		(comment 1 "Bryce Canyon / footprints 320-326 of 2223")
	)
	(layers
		(0 "F.Cu" signal "TOP")
		(4 "In1.Cu" signal "L2GND")
		(6 "In2.Cu" signal "L3")
		(8 "In3.Cu" signal "L4GND")
		(10 "In4.Cu" signal "L5")
		(12 "In5.Cu" signal "L6VCC")
		(14 "In6.Cu" signal "L7VCC")
		(16 "In7.Cu" signal "L8")
		(18 "In8.Cu" signal "L9GND")
		(20 "In9.Cu" signal "L10")
		(22 "In10.Cu" signal "L11GND")
		(2 "B.Cu" signal "BOTTOM")
		(9 "F.Adhes" user "F.Adhesive")
		(11 "B.Adhes" user "B.Adhesive")
		(13 "F.Paste" user "Package Geometry/Pastemask Top")
		(15 "B.Paste" user "Package Geometry/Pastemask Bottom")
		(5 "F.SilkS" user "Ref Des/Silkscreen Top")
		(7 "B.SilkS" user "Ref Des/Silkscreen Bottom")
		(1 "F.Mask" user "Board Geometry/Soldermask Top")
		(3 "B.Mask" user "Board Geometry/Soldermask Bottom")
		(17 "Dwgs.User" user "User.Drawings")
		(19 "Cmts.User" user "User.Comments")
		(21 "Eco1.User" user "User.Eco1")
		(23 "Eco2.User" user "User.Eco2")
		(25 "Edge.Cuts" user "Board Geometry/Outline")
		(27 "Margin" user)
		(31 "F.CrtYd" user "Package Geometry/Place Bound Top")
		(29 "B.CrtYd" user "Package Geometry/Place Bound Bottom")
		(35 "F.Fab" user "Ref Des/Assembly Top")
		(33 "B.Fab" user "Ref Des/Assembly Bottom")
	)
	(footprint ""
		(layer "F.Cu")
		(at 11.106912 -127.808736 180)
		(property "Reference" "Q275"
			(at 0 0 180)
			(layer "F.SilkS")
			(hide yes)
			(effects
				(font
					(size 1.27 1.27)
				)
			)
		)
		(property "Value" "SSM3K324R-GP"
			(at 0.127 -8.9662 180)
			(unlocked yes)
			(layer "F.Fab")
			(hide yes)
			(effects
				(font
					(size 1.016 1.016)
					(thickness 0.1524)
				)
			)
		)
		(property "Device Type" "SOT23DGS2D4H35"
			(at 0.127 -10.4902 180)
			(unlocked yes)
			(layer "F.Fab")
			(hide yes)
			(effects
				(font
					(size 1.016 1.016)
					(thickness 0.1524)
				)
			)
		)
		(duplicate_pad_numbers_are_jumpers no)
		(fp_line
			(start 1.651 1.778)
			(end 1.651 -1.778)
			(stroke
				(width 0.1524)
				(type default)
			)
			(layer "F.SilkS")
		)
		(fp_line
			(start 1.651 -1.778)
			(end -1.651 -1.778)
			(stroke
				(width 0.1524)
				(type default)
			)
			(layer "F.SilkS")
		)
		(fp_line
			(start -1.651 1.778)
			(end 1.651 1.778)
			(stroke
				(width 0.1524)
				(type default)
			)
			(layer "F.SilkS")
		)
		(fp_line
			(start -1.651 -1.778)
			(end -1.651 1.778)
			(stroke
				(width 0.1524)
				(type default)
			)
			(layer "F.SilkS")
		)
		(fp_poly
			(pts
				(xy -1.778 1.8796) (xy -1.778 -1.8796) (xy 1.778 -1.8796) (xy 1.778 1.8796)
			)
			(stroke
				(width 0)
				(type default)
			)
			(fill no)
			(layer "F.CrtYd")
		)
		(fp_poly
			(pts
				(xy -1.778 1.8796) (xy -1.778 -1.8796) (xy 1.778 -1.8796) (xy 1.778 1.8796)
			)
			(stroke
				(width 0)
				(type default)
			)
			(fill no)
			(layer "F.Fab")
		)
		(pad "D" smd custom
			(at 0 -0.9525 180)
			(size 0.1905 0.1905)
			(layers "F.Cu" "F.Mask" "F.Paste")
			(net "DRV_ACT_12_N")
			(options
				(clearance outline)
				(anchor circle)
			)
			(primitives
				(gr_poly
					(pts
						(arc
							(start -0.1778 0.5715)
							(mid -0.321484 0.511984)
							(end -0.381 0.3683)
						)
						(arc
							(start -0.381 -0.3683)
							(mid -0.321484 -0.511984)
							(end -0.1778 -0.5715)
						)
						(arc
							(start 0.1778 -0.5715)
							(mid 0.321484 -0.511984)
							(end 0.381 -0.3683)
						)
						(arc
							(start 0.381 0.3683)
							(mid 0.321484 0.511984)
							(end 0.1778 0.5715)
						)
					)
					(width 0)
					(fill yes)
				)
			)
		)
		(pad "G" smd custom
			(at -0.98425 0.9525 180)
			(size 0.1905 0.1905)
			(layers "F.Cu" "F.Mask" "F.Paste")
			(net "DRIVE_A_12_ACT")
			(options
				(clearance outline)
				(anchor circle)
			)
			(primitives
				(gr_poly
					(pts
						(arc
							(start -0.1778 0.5715)
							(mid -0.321484 0.511984)
							(end -0.381 0.3683)
						)
						(arc
							(start -0.381 -0.3683)
							(mid -0.321484 -0.511984)
							(end -0.1778 -0.5715)
						)
						(arc
							(start 0.1778 -0.5715)
							(mid 0.321484 -0.511984)
							(end 0.381 -0.3683)
						)
						(arc
							(start 0.381 0.3683)
							(mid 0.321484 0.511984)
							(end 0.1778 0.5715)
						)
					)
					(width 0)
					(fill yes)
				)
			)
		)
		(pad "S" smd custom
			(at 0.98425 0.9525 180)
			(size 0.1905 0.1905)
			(layers "F.Cu" "F.Mask" "F.Paste")
			(net "GND")
			(options
				(clearance outline)
				(anchor circle)
			)
			(primitives
				(gr_poly
					(pts
						(arc
							(start -0.1778 0.5715)
							(mid -0.321484 0.511984)
							(end -0.381 0.3683)
						)
						(arc
							(start -0.381 -0.3683)
							(mid -0.321484 -0.511984)
							(end -0.1778 -0.5715)
						)
						(arc
							(start 0.1778 -0.5715)
							(mid 0.321484 -0.511984)
							(end 0.381 -0.3683)
						)
						(arc
							(start 0.381 0.3683)
							(mid 0.321484 0.511984)
							(end 0.1778 0.5715)
						)
					)
					(width 0)
					(fill yes)
				)
			)
		)
	)
	(footprint ""
		(layer "F.Cu")
		(at 234.5944 -231.3178)
		(property "Reference" "R65"
			(at 0 0 0)
			(layer "F.SilkS")
			(hide yes)
			(effects
				(font
					(size 1.27 1.27)
				)
			)
		)
		(property "Value" "0R2J-2-GP"
			(at 0.064008 -3.993896 0)
			(unlocked yes)
			(layer "F.Fab")
			(hide yes)
			(effects
				(font
					(size 1.016 1.016)
					(thickness 0.1524)
				)
			)
		)
		(property "Device Type" "R402H16"
			(at 0.064008 -5.517896 0)
			(unlocked yes)
			(layer "F.Fab")
			(hide yes)
			(effects
				(font
					(size 1.016 1.016)
					(thickness 0.1524)
				)
			)
		)
		(duplicate_pad_numbers_are_jumpers no)
		(fp_line
			(start -0.508 -0.9398)
			(end -0.508 0.9398)
			(stroke
				(width 0.1524)
				(type default)
			)
			(layer "F.SilkS")
		)
		(fp_line
			(start 0.508 -0.9398)
			(end -0.508 -0.9398)
			(stroke
				(width 0.1524)
				(type default)
			)
			(layer "F.SilkS")
		)
		(fp_rect
			(start -0.508 0.9398)
			(end 0.508 -0.9398)
			(stroke
				(width 0)
				(type default)
			)
			(fill no)
			(layer "F.CrtYd")
		)
		(fp_rect
			(start -0.508 0.9398)
			(end 0.508 -0.9398)
			(stroke
				(width 0)
				(type default)
			)
			(fill no)
			(layer "F.Fab")
		)
		(pad "1" smd custom
			(at 0 -0.4445)
			(size 0.1397 0.1397)
			(layers "F.Cu" "F.Mask" "F.Paste")
			(net "IO_EXP1_SCL")
			(options
				(clearance outline)
				(anchor circle)
			)
			(primitives
				(gr_poly
					(pts
						(arc
							(start -0.1778 -0.2794)
							(mid -0.249642 -0.249642)
							(end -0.2794 -0.1778)
						)
						(arc
							(start -0.2794 0.1778)
							(mid -0.249642 0.249642)
							(end -0.1778 0.2794)
						)
						(arc
							(start 0.1778 0.2794)
							(mid 0.249642 0.249642)
							(end 0.2794 0.1778)
						)
						(arc
							(start 0.2794 -0.1778)
							(mid 0.249642 -0.249642)
							(end 0.1778 -0.2794)
						)
					)
					(width 0)
					(fill yes)
				)
			)
		)
		(pad "2" smd custom
			(at 0 0.4445)
			(size 0.1397 0.1397)
			(layers "F.Cu" "F.Mask" "F.Paste")
			(net "I2C_DRIVE_A_PWR_SCL")
			(options
				(clearance outline)
				(anchor circle)
			)
			(primitives
				(gr_poly
					(pts
						(arc
							(start -0.1778 -0.2794)
							(mid -0.249642 -0.249642)
							(end -0.2794 -0.1778)
						)
						(arc
							(start -0.2794 0.1778)
							(mid -0.249642 0.249642)
							(end -0.1778 0.2794)
						)
						(arc
							(start 0.1778 0.2794)
							(mid 0.249642 0.249642)
							(end 0.2794 0.1778)
						)
						(arc
							(start 0.2794 -0.1778)
							(mid 0.249642 -0.249642)
							(end 0.1778 -0.2794)
						)
					)
					(width 0)
					(fill yes)
				)
			)
		)
	)
	(footprint ""
		(layer "F.Cu")
		(at 272.542 -354.104956 180)
		(property "Reference" "VIA39"
			(at 0 0 180)
			(layer "F.SilkS")
			(hide yes)
			(effects
				(font
					(size 1.27 1.27)
				)
			)
		)
		(property "Value" "100OHM-8L-1D6MM-L18L16-GP"
			(at -3.7211 -4.5085 180)
			(unlocked yes)
			(layer "F.Fab")
			(hide yes)
			(effects
				(font
					(size 1.016 1.016)
					(thickness 0.1524)
				)
			)
		)
		(property "Device Type" "VIA-PCIE-4P-394076"
			(at -3.7211 -6.0325 180)
			(unlocked yes)
			(layer "F.Fab")
			(hide yes)
			(effects
				(font
					(size 1.016 1.016)
					(thickness 0.1524)
				)
			)
		)
		(duplicate_pad_numbers_are_jumpers no)
		(fp_rect
			(start -1.9685 0.381)
			(end 1.9685 -0.381)
			(stroke
				(width 0)
				(type default)
			)
			(fill no)
			(layer "F.CrtYd")
		)
		(fp_rect
			(start -1.9685 0.381)
			(end 1.9685 -0.381)
			(stroke
				(width 0)
				(type default)
			)
			(fill no)
			(layer "F.Fab")
		)
		(pad "1" thru_hole circle
			(at -1.5875 0 180)
			(size 0.508 0.508)
			(drill 0.254)
			(layers "*.Cu" "*.Mask")
			(remove_unused_layers no)
			(net "GND")
			(clearance 0.127)
			(thermal_gap 0.127)
		)
		(pad "2" thru_hole circle
			(at -0.5715 0 180)
			(size 0.508 0.508)
			(drill 0.254)
			(layers "*.Cu" "*.Mask")
			(remove_unused_layers no)
			(net "PHY_SCC_A_TO_DRV_A_3_DP")
			(clearance 0.127)
			(thermal_gap 0.127)
		)
		(pad "3" thru_hole circle
			(at 0.5715 0 180)
			(size 0.508 0.508)
			(drill 0.254)
			(layers "*.Cu" "*.Mask")
			(remove_unused_layers no)
			(net "PHY_SCC_A_TO_DRV_A_3_DN")
			(clearance 0.127)
			(thermal_gap 0.127)
		)
		(pad "4" thru_hole circle
			(at 1.5875 0 180)
			(size 0.508 0.508)
			(drill 0.254)
			(layers "*.Cu" "*.Mask")
			(remove_unused_layers no)
			(net "GND")
			(clearance 0.127)
			(thermal_gap 0.127)
		)
	)
	(footprint ""
		(layer "F.Cu")
		(at 52.213002 -150.78075 -90)
		(property "Reference" "R1225"
			(at 0 0 270)
			(layer "F.SilkS")
			(hide yes)
			(effects
				(font
					(size 1.27 1.27)
				)
			)
		)
		(property "Value" "0R2J-2-GP"
			(at 0.064008 -3.993896 270)
			(unlocked yes)
			(layer "F.Fab")
			(hide yes)
			(effects
				(font
					(size 1.016 1.016)
					(thickness 0.1524)
				)
			)
		)
		(property "Device Type" "R402H16"
			(at 0.064008 -5.517896 270)
			(unlocked yes)
			(layer "F.Fab")
			(hide yes)
			(effects
				(font
					(size 1.016 1.016)
					(thickness 0.1524)
				)
			)
		)
		(duplicate_pad_numbers_are_jumpers no)
		(fp_line
			(start -0.508 -0.9398)
			(end -0.508 0.9398)
			(stroke
				(width 0.1524)
				(type default)
			)
			(layer "F.SilkS")
		)
		(fp_line
			(start 0.508 -0.9398)
			(end -0.508 -0.9398)
			(stroke
				(width 0.1524)
				(type default)
			)
			(layer "F.SilkS")
		)
		(fp_rect
			(start -0.508 0.9398)
			(end 0.508 -0.9398)
			(stroke
				(width 0)
				(type default)
			)
			(fill no)
			(layer "F.CrtYd")
		)
		(fp_rect
			(start -0.508 0.9398)
			(end 0.508 -0.9398)
			(stroke
				(width 0)
				(type default)
			)
			(fill no)
			(layer "F.Fab")
		)
		(pad "1" smd custom
			(at 0 -0.4445 270)
			(size 0.1397 0.1397)
			(layers "F.Cu" "F.Mask" "F.Paste")
			(net "P12V_A_PGOOD")
			(options
				(clearance outline)
				(anchor circle)
			)
			(primitives
				(gr_poly
					(pts
						(arc
							(start -0.1778 -0.2794)
							(mid -0.249642 -0.249642)
							(end -0.2794 -0.1778)
						)
						(arc
							(start -0.2794 0.1778)
							(mid -0.249642 0.249642)
							(end -0.1778 0.2794)
						)
						(arc
							(start 0.1778 0.2794)
							(mid 0.249642 0.249642)
							(end 0.2794 0.1778)
						)
						(arc
							(start 0.2794 -0.1778)
							(mid 0.249642 -0.249642)
							(end 0.1778 -0.2794)
						)
					)
					(width 0)
					(fill yes)
				)
			)
		)
		(pad "2" smd custom
			(at 0 0.4445 270)
			(size 0.1397 0.1397)
			(layers "F.Cu" "F.Mask" "F.Paste")
			(net "P5V_B_EN_R")
			(options
				(clearance outline)
				(anchor circle)
			)
			(primitives
				(gr_poly
					(pts
						(arc
							(start -0.1778 -0.2794)
							(mid -0.249642 -0.249642)
							(end -0.2794 -0.1778)
						)
						(arc
							(start -0.2794 0.1778)
							(mid -0.249642 0.249642)
							(end -0.1778 0.2794)
						)
						(arc
							(start 0.1778 0.2794)
							(mid 0.249642 0.249642)
							(end 0.2794 0.1778)
						)
						(arc
							(start 0.2794 -0.1778)
							(mid 0.249642 -0.249642)
							(end 0.1778 -0.2794)
						)
					)
					(width 0)
					(fill yes)
				)
			)
		)
	)
	(footprint ""
		(layer "F.Cu")
		(at 14.842998 -284.523942 90)
		(property "Reference" "C517"
			(at 0 0 90)
			(layer "F.SilkS")
			(hide yes)
			(effects
				(font
					(size 1.27 1.27)
				)
			)
		)
		(property "Value" "SCD033U25V2KX-GP"
			(at 1.1811 -2.7051 90)
			(unlocked yes)
			(layer "F.Fab")
			(hide yes)
			(effects
				(font
					(size 1.016 1.016)
					(thickness 0.1524)
				)
			)
		)
		(property "Device Type" "C402H22"
			(at 1.1811 -4.2291 90)
			(unlocked yes)
			(layer "F.Fab")
			(hide yes)
			(effects
				(font
					(size 1.016 1.016)
					(thickness 0.1524)
				)
			)
		)
		(duplicate_pad_numbers_are_jumpers no)
		(fp_rect
			(start -0.4318 0.9525)
			(end 0.4318 -0.9525)
			(stroke
				(width 0)
				(type default)
			)
			(fill no)
			(layer "F.CrtYd")
		)
		(fp_rect
			(start -0.4318 0.9525)
			(end 0.4318 -0.9525)
			(stroke
				(width 0)
				(type default)
			)
			(fill no)
			(layer "F.Fab")
		)
		(pad "1" smd custom
			(at 0 -0.4445 90)
			(size 0.1524 0.1524)
			(layers "F.Cu" "F.Mask" "F.Paste")
			(net "P12V_A")
			(options
				(clearance outline)
				(anchor circle)
			)
			(primitives
				(gr_poly
					(pts
						(arc
							(start 0.3048 -0.2032)
							(mid 0.275042 -0.275042)
							(end 0.2032 -0.3048)
						)
						(arc
							(start -0.2032 -0.3048)
							(mid -0.275042 -0.275042)
							(end -0.3048 -0.2032)
						)
						(arc
							(start -0.3048 0.2032)
							(mid -0.275042 0.275042)
							(end -0.2032 0.3048)
						)
						(arc
							(start 0.2032 0.3048)
							(mid 0.275042 0.275042)
							(end 0.3048 0.2032)
						)
					)
					(width 0)
					(fill yes)
				)
			)
		)
		(pad "2" smd custom
			(at 0 0.4445 90)
			(size 0.1524 0.1524)
			(layers "F.Cu" "F.Mask" "F.Paste")
			(net "SW_HDD_N0")
			(options
				(clearance outline)
				(anchor circle)
			)
			(primitives
				(gr_poly
					(pts
						(arc
							(start 0.3048 -0.2032)
							(mid 0.275042 -0.275042)
							(end 0.2032 -0.3048)
						)
						(arc
							(start -0.2032 -0.3048)
							(mid -0.275042 -0.275042)
							(end -0.3048 -0.2032)
						)
						(arc
							(start -0.3048 0.2032)
							(mid -0.275042 0.275042)
							(end -0.2032 0.3048)
						)
						(arc
							(start 0.2032 0.3048)
							(mid 0.275042 0.275042)
							(end 0.3048 0.2032)
						)
					)
					(width 0)
					(fill yes)
				)
			)
		)
	)
	(footprint ""
		(layer "F.Cu")
		(at 479.384614 -158.660592 -90)
		(property "Reference" "C338"
			(at 0 0 270)
			(layer "F.SilkS")
			(hide yes)
			(effects
				(font
					(size 1.27 1.27)
				)
			)
		)
		(property "Value" "SCD01U16V1KX-GP"
			(at -2.8321 -1.7399 270)
			(unlocked yes)
			(layer "F.Fab")
			(hide yes)
			(effects
				(font
					(size 1.016 1.016)
					(thickness 0.1524)
				)
			)
		)
		(property "Device Type" "C0201H13"
			(at -2.8321 -3.2639 270)
			(unlocked yes)
			(layer "F.Fab")
			(hide yes)
			(effects
				(font
					(size 1.016 1.016)
					(thickness 0.1524)
				)
			)
		)
		(duplicate_pad_numbers_are_jumpers no)
		(fp_rect
			(start -0.2794 0.6477)
			(end 0.2794 -0.6477)
			(stroke
				(width 0)
				(type default)
			)
			(fill no)
			(layer "F.CrtYd")
		)
		(fp_rect
			(start -0.2794 0.6477)
			(end 0.2794 -0.6477)
			(stroke
				(width 0)
				(type default)
			)
			(fill no)
			(layer "F.Fab")
		)
		(pad "1" smd custom
			(at 0 -0.2794 270)
			(size 0.0762 0.0762)
			(layers "F.Cu" "F.Mask" "F.Paste")
			(net "SAS_HDD_RX_P23")
			(options
				(clearance outline)
				(anchor circle)
			)
			(primitives
				(gr_poly
					(pts
						(arc
							(start 0.1524 -0.127)
							(mid 0.137521 -0.162921)
							(end 0.1016 -0.1778)
						)
						(arc
							(start -0.1016 -0.1778)
							(mid -0.137521 -0.162921)
							(end -0.1524 -0.127)
						)
						(arc
							(start -0.1524 0.127)
							(mid -0.137521 0.162921)
							(end -0.1016 0.1778)
						)
						(arc
							(start 0.1016 0.1778)
							(mid 0.137521 0.162921)
							(end 0.1524 0.127)
						)
					)
					(width 0)
					(fill yes)
				)
			)
		)
		(pad "2" smd custom
			(at 0 0.2794 270)
			(size 0.0762 0.0762)
			(layers "F.Cu" "F.Mask" "F.Paste")
			(net "PHY_SCC_A_TO_DRV_A_23_DP")
			(options
				(clearance outline)
				(anchor circle)
			)
			(primitives
				(gr_poly
					(pts
						(arc
							(start 0.1524 -0.127)
							(mid 0.137521 -0.162921)
							(end 0.1016 -0.1778)
						)
						(arc
							(start -0.1016 -0.1778)
							(mid -0.137521 -0.162921)
							(end -0.1524 -0.127)
						)
						(arc
							(start -0.1524 0.127)
							(mid -0.137521 0.162921)
							(end -0.1016 0.1778)
						)
						(arc
							(start 0.1016 0.1778)
							(mid 0.137521 0.162921)
							(end 0.1524 0.127)
						)
					)
					(width 0)
					(fill yes)
				)
			)
		)
	)
	(footprint ""
		(layer "F.Cu")
		(at 173.6725 -160.506918 90)
		(property "Reference" "R535"
			(at 0 0 90)
			(layer "F.SilkS")
			(hide yes)
			(effects
				(font
					(size 1.27 1.27)
				)
			)
		)
		(property "Value" "4K7R2J-2-GP"
			(at 0.064008 -3.993896 90)
			(unlocked yes)
			(layer "F.Fab")
			(hide yes)
			(effects
				(font
					(size 1.016 1.016)
					(thickness 0.1524)
				)
			)
		)
		(property "Device Type" "R402H16"
			(at 0.064008 -5.517896 90)
			(unlocked yes)
			(layer "F.Fab")
			(hide yes)
			(effects
				(font
					(size 1.016 1.016)
					(thickness 0.1524)
				)
			)
		)
		(duplicate_pad_numbers_are_jumpers no)
		(fp_line
			(start 0.508 -0.9398)
			(end -0.508 -0.9398)
			(stroke
				(width 0.1524)
				(type default)
			)
			(layer "F.SilkS")
		)
		(fp_line
			(start -0.508 -0.9398)
			(end -0.508 0.9398)
			(stroke
				(width 0.1524)
				(type default)
			)
			(layer "F.SilkS")
		)
		(fp_rect
			(start -0.508 0.9398)
			(end 0.508 -0.9398)
			(stroke
				(width 0)
				(type default)
			)
			(fill no)
			(layer "F.CrtYd")
		)
		(fp_rect
			(start -0.508 0.9398)
			(end 0.508 -0.9398)
			(stroke
				(width 0)
				(type default)
			)
			(fill no)
			(layer "F.Fab")
		)
		(pad "1" smd custom
			(at 0 -0.4445 90)
			(size 0.1397 0.1397)
			(layers "F.Cu" "F.Mask" "F.Paste")
			(net "P12V_A")
			(options
				(clearance outline)
				(anchor circle)
			)
			(primitives
				(gr_poly
					(pts
						(arc
							(start -0.1778 -0.2794)
							(mid -0.249642 -0.249642)
							(end -0.2794 -0.1778)
						)
						(arc
							(start -0.2794 0.1778)
							(mid -0.249642 0.249642)
							(end -0.1778 0.2794)
						)
						(arc
							(start 0.1778 0.2794)
							(mid 0.249642 0.249642)
							(end 0.2794 0.1778)
						)
						(arc
							(start 0.2794 -0.1778)
							(mid 0.249642 -0.249642)
							(end 0.1778 -0.2794)
						)
					)
					(width 0)
					(fill yes)
				)
			)
		)
		(pad "2" smd custom
			(at 0 0.4445 90)
			(size 0.1397 0.1397)
			(layers "F.Cu" "F.Mask" "F.Paste")
			(net "SW_HDD_R17")
			(options
				(clearance outline)
				(anchor circle)
			)
			(primitives
				(gr_poly
					(pts
						(arc
							(start -0.1778 -0.2794)
							(mid -0.249642 -0.249642)
							(end -0.2794 -0.1778)
						)
						(arc
							(start -0.2794 0.1778)
							(mid -0.249642 0.249642)
							(end -0.1778 0.2794)
						)
						(arc
							(start 0.1778 0.2794)
							(mid 0.249642 0.249642)
							(end 0.2794 0.1778)
						)
						(arc
							(start 0.2794 -0.1778)
							(mid 0.249642 -0.249642)
							(end 0.1778 -0.2794)
						)
					)
					(width 0)
					(fill yes)
				)
			)
		)
	)
)
